(kicad_pcb
	(version 20260206)
	(generator "pcbnew")
	(generator_version "10.0")
	(general
		(thickness 1.6)
		(legacy_teardrops no)
	)
	(paper "A4")
	(title_block
		(title "03242023_DA0F0TMBIJ0_F0T_Motherboard_J_brd_V01_OCP.brd")
		(comment 1 "Grand Teton / footprints 941-947 of 6105")
	)
	(layers
		(0 "F.Cu" signal "TOP")
		(4 "In1.Cu" signal "GND")
		(6 "In2.Cu" signal "IN1")
		(8 "In3.Cu" signal "GND1")
		(10 "In4.Cu" signal "IN2")
		(12 "In5.Cu" signal "GND2")
		(14 "In6.Cu" signal "IN3")
		(16 "In7.Cu" signal "GND3")
		(18 "In8.Cu" signal "VCC")
		(20 "In9.Cu" signal "VCC1")
		(22 "In10.Cu" signal "GND4")
		(24 "In11.Cu" signal "IN4")
		(26 "In12.Cu" signal "GND5")
		(28 "In13.Cu" signal "IN5")
		(30 "In14.Cu" signal "GND6")
		(32 "In15.Cu" signal "IN6")
		(34 "In16.Cu" signal "GND7")
		(2 "B.Cu" signal "BOTTOM")
		(9 "F.Adhes" user "F.Adhesive")
		(11 "B.Adhes" user "B.Adhesive")
		(13 "F.Paste" user "Package Geometry/Pastemask Top")
		(15 "B.Paste" user "Package Geometry/Pastemask Bottom")
		(5 "F.SilkS" user "Ref Des/Silkscreen Top")
		(7 "B.SilkS" user "Ref Des/Silkscreen Bottom")
		(1 "F.Mask" user "Board Geometry/Soldermask Top")
		(3 "B.Mask" user "Board Geometry/Soldermask Bottom")
		(17 "Dwgs.User" user "User.Drawings")
		(19 "Cmts.User" user "User.Comments")
		(21 "Eco1.User" user "User.Eco1")
		(23 "Eco2.User" user "User.Eco2")
		(25 "Edge.Cuts" user "Board Geometry/Outline")
		(27 "Margin" user)
		(31 "F.CrtYd" user "Package Geometry/Place Bound Top")
		(29 "B.CrtYd" user "Package Geometry/Place Bound Bottom")
		(35 "F.Fab" user "Ref Des/Assembly Top")
		(33 "B.Fab" user "Ref Des/Assembly Bottom")
	)
	(footprint ""
		(layer "F.Cu")
		(at 66.333878 -402.371052 -90)
		(property "Reference" "C722"
			(at 0 0 270)
			(layer "F.SilkS")
			(hide yes)
			(effects
				(font
					(size 1.27 1.27)
				)
			)
		)
		(property "Value" ""
			(at 0 0 270)
			(layer "F.Fab")
			(effects
				(font
					(size 1.27 1.27)
				)
			)
		)
		(duplicate_pad_numbers_are_jumpers no)
		(fp_line
			(start -0.299974 0.150114)
			(end -0.299974 -0.150114)
			(stroke
				(width 0.1)
				(type default)
			)
			(layer "F.Fab")
		)
		(fp_line
			(start 0.299974 0.150114)
			(end -0.299974 0.150114)
			(stroke
				(width 0.1)
				(type default)
			)
			(layer "F.Fab")
		)
		(fp_line
			(start -0.299974 -0.150114)
			(end 0.299974 -0.150114)
			(stroke
				(width 0.1)
				(type default)
			)
			(layer "F.Fab")
		)
		(fp_line
			(start 0.299974 -0.150114)
			(end 0.299974 0.150114)
			(stroke
				(width 0.1)
				(type default)
			)
			(layer "F.Fab")
		)
		(pad "1" smd rect
			(at -0.2667 0 270)
			(size 0.3048 0.381)
			(layers "F.Cu" "F.Mask" "F.Paste")
			(net "P5E_CPU1_PE0_TX_C_DN<9>")
		)
		(pad "2" smd rect
			(at 0.2667 0 270)
			(size 0.3048 0.381)
			(layers "F.Cu" "F.Mask" "F.Paste")
			(net "P5E_CPU1_PE0_TX_DN<9>")
		)
	)
	(footprint ""
		(layer "F.Cu")
		(at 461.957928 -94.317566)
		(property "Reference" "C1840"
			(at 0 0 0)
			(layer "F.SilkS")
			(hide yes)
			(effects
				(font
					(size 1.27 1.27)
				)
			)
		)
		(property "Value" ""
			(at 0 0 0)
			(layer "F.Fab")
			(effects
				(font
					(size 1.27 1.27)
				)
			)
		)
		(duplicate_pad_numbers_are_jumpers no)
		(fp_line
			(start -0.7874 -0.4064)
			(end 0.7874 -0.4064)
			(stroke
				(width 0.1524)
				(type default)
			)
			(layer "F.SilkS")
		)
		(fp_line
			(start -0.7874 0.4064)
			(end -0.7874 -0.4064)
			(stroke
				(width 0.1524)
				(type default)
			)
			(layer "F.SilkS")
		)
		(fp_line
			(start 0.7874 -0.4064)
			(end 0.7874 0.4064)
			(stroke
				(width 0.1524)
				(type default)
			)
			(layer "F.SilkS")
		)
		(fp_line
			(start 0.7874 0.4064)
			(end -0.7874 0.4064)
			(stroke
				(width 0.1524)
				(type default)
			)
			(layer "F.SilkS")
		)
		(fp_line
			(start -0.67945 -0.305054)
			(end -0.12065 -0.305054)
			(stroke
				(width 0.1)
				(type default)
			)
			(layer "F.Fab")
		)
		(fp_line
			(start -0.67945 0.3048)
			(end -0.67945 -0.305054)
			(stroke
				(width 0.1)
				(type default)
			)
			(layer "F.Fab")
		)
		(fp_line
			(start -0.12065 -0.305054)
			(end -0.12065 -0.2794)
			(stroke
				(width 0.1)
				(type default)
			)
			(layer "F.Fab")
		)
		(fp_line
			(start -0.12065 -0.2794)
			(end 0.12065 -0.2794)
			(stroke
				(width 0.1)
				(type default)
			)
			(layer "F.Fab")
		)
		(fp_line
			(start -0.12065 0.2794)
			(end -0.12065 0.3048)
			(stroke
				(width 0.1)
				(type default)
			)
			(layer "F.Fab")
		)
		(fp_line
			(start -0.12065 0.3048)
			(end -0.67945 0.3048)
			(stroke
				(width 0.1)
				(type default)
			)
			(layer "F.Fab")
		)
		(fp_line
			(start 0.120396 0.2794)
			(end -0.12065 0.2794)
			(stroke
				(width 0.1)
				(type default)
			)
			(layer "F.Fab")
		)
		(fp_line
			(start 0.120396 0.3048)
			(end 0.120396 0.2794)
			(stroke
				(width 0.1)
				(type default)
			)
			(layer "F.Fab")
		)
		(fp_line
			(start 0.12065 -0.3048)
			(end 0.67945 -0.3048)
			(stroke
				(width 0.1)
				(type default)
			)
			(layer "F.Fab")
		)
		(fp_line
			(start 0.12065 -0.2794)
			(end 0.12065 -0.3048)
			(stroke
				(width 0.1)
				(type default)
			)
			(layer "F.Fab")
		)
		(fp_line
			(start 0.67945 -0.3048)
			(end 0.67945 0.3048)
			(stroke
				(width 0.1)
				(type default)
			)
			(layer "F.Fab")
		)
		(fp_line
			(start 0.67945 0.3048)
			(end 0.120396 0.3048)
			(stroke
				(width 0.1)
				(type default)
			)
			(layer "F.Fab")
		)
		(pad "1" smd circle
			(at -0.40005 0)
			(size 0 0)
			(layers "F.Cu" "F.Mask" "F.Paste")
			(net "P3V3_AUX")
		)
		(pad "2" smd circle
			(at 0.40005 0)
			(size 0 0)
			(layers "F.Cu" "F.Mask" "F.Paste")
			(net "GND")
		)
	)
	(footprint ""
		(layer "F.Cu")
		(at 241.308128 -110.240572 180)
		(property "Reference" "R1016"
			(at 0 0 180)
			(layer "F.SilkS")
			(hide yes)
			(effects
				(font
					(size 1.27 1.27)
				)
			)
		)
		(property "Value" ""
			(at 0 0 180)
			(layer "F.Fab")
			(effects
				(font
					(size 1.27 1.27)
				)
			)
		)
		(duplicate_pad_numbers_are_jumpers no)
		(fp_line
			(start 0.7874 0.4064)
			(end -0.7874 0.4064)
			(stroke
				(width 0.1524)
				(type default)
			)
			(layer "F.SilkS")
		)
		(fp_line
			(start 0.7874 -0.4064)
			(end 0.7874 0.4064)
			(stroke
				(width 0.1524)
				(type default)
			)
			(layer "F.SilkS")
		)
		(fp_line
			(start -0.7874 0.4064)
			(end -0.7874 -0.4064)
			(stroke
				(width 0.1524)
				(type default)
			)
			(layer "F.SilkS")
		)
		(fp_line
			(start -0.7874 -0.4064)
			(end 0.7874 -0.4064)
			(stroke
				(width 0.1524)
				(type default)
			)
			(layer "F.SilkS")
		)
		(fp_line
			(start 0.67945 0.3048)
			(end 0.120396 0.3048)
			(stroke
				(width 0.1)
				(type default)
			)
			(layer "F.Fab")
		)
		(fp_line
			(start 0.67945 -0.3048)
			(end 0.67945 0.3048)
			(stroke
				(width 0.1)
				(type default)
			)
			(layer "F.Fab")
		)
		(fp_line
			(start 0.12065 -0.2794)
			(end 0.12065 -0.3048)
			(stroke
				(width 0.1)
				(type default)
			)
			(layer "F.Fab")
		)
		(fp_line
			(start 0.12065 -0.3048)
			(end 0.67945 -0.3048)
			(stroke
				(width 0.1)
				(type default)
			)
			(layer "F.Fab")
		)
		(fp_line
			(start 0.120396 0.3048)
			(end 0.120396 0.2794)
			(stroke
				(width 0.1)
				(type default)
			)
			(layer "F.Fab")
		)
		(fp_line
			(start 0.120396 0.2794)
			(end -0.12065 0.2794)
			(stroke
				(width 0.1)
				(type default)
			)
			(layer "F.Fab")
		)
		(fp_line
			(start -0.12065 0.3048)
			(end -0.67945 0.3048)
			(stroke
				(width 0.1)
				(type default)
			)
			(layer "F.Fab")
		)
		(fp_line
			(start -0.12065 0.2794)
			(end -0.12065 0.3048)
			(stroke
				(width 0.1)
				(type default)
			)
			(layer "F.Fab")
		)
		(fp_line
			(start -0.12065 -0.2794)
			(end 0.12065 -0.2794)
			(stroke
				(width 0.1)
				(type default)
			)
			(layer "F.Fab")
		)
		(fp_line
			(start -0.12065 -0.305054)
			(end -0.12065 -0.2794)
			(stroke
				(width 0.1)
				(type default)
			)
			(layer "F.Fab")
		)
		(fp_line
			(start -0.67945 0.3048)
			(end -0.67945 -0.305054)
			(stroke
				(width 0.1)
				(type default)
			)
			(layer "F.Fab")
		)
		(fp_line
			(start -0.67945 -0.305054)
			(end -0.12065 -0.305054)
			(stroke
				(width 0.1)
				(type default)
			)
			(layer "F.Fab")
		)
		(pad "1" smd circle
			(at -0.40005 0 180)
			(size 0 0)
			(layers "F.Cu" "F.Mask" "F.Paste")
			(net "CLK_25M_CK440_CPU1_DP")
		)
		(pad "2" smd circle
			(at 0.40005 0 180)
			(size 0 0)
			(layers "F.Cu" "F.Mask" "F.Paste")
			(net "CLK_25M_CK440_CPU1_R_DP")
		)
	)
	(footprint ""
		(layer "F.Cu")
		(at 93.782896 -70.78599)
		(property "Reference" "D87"
			(at -47.431706 50.178462 90)
			(unlocked yes)
			(layer "F.SilkS")
			(effects
				(font
					(size 0.635 0.4064)
					(thickness 0.1524)
				)
				(justify left)
			)
		)
		(property "Value" ""
			(at 0 0 0)
			(layer "F.Fab")
			(effects
				(font
					(size 1.27 1.27)
				)
			)
		)
		(duplicate_pad_numbers_are_jumpers no)
		(fp_line
			(start -0.90678 0.4826)
			(end -0.90678 -0.4699)
			(stroke
				(width 0.1524)
				(type default)
			)
			(layer "F.SilkS")
		)
		(fp_line
			(start -0.89408 -0.4826)
			(end 0.90678 -0.4826)
			(stroke
				(width 0.1524)
				(type default)
			)
			(layer "F.SilkS")
		)
		(fp_line
			(start -0.79248 -0.4826)
			(end 1.03378 -0.4826)
			(stroke
				(width 0.1524)
				(type default)
			)
			(layer "F.SilkS")
		)
		(fp_line
			(start -0.64008 -0.4826)
			(end 1.16078 -0.4826)
			(stroke
				(width 0.1524)
				(type default)
			)
			(layer "F.SilkS")
		)
		(fp_line
			(start 0.90678 -0.4826)
			(end 0.90678 0.4826)
			(stroke
				(width 0.1524)
				(type default)
			)
			(layer "F.SilkS")
		)
		(fp_line
			(start 0.90678 0.4826)
			(end -0.90678 0.4826)
			(stroke
				(width 0.1524)
				(type default)
			)
			(layer "F.SilkS")
		)
		(fp_line
			(start 1.03378 -0.4826)
			(end 1.03378 0.4826)
			(stroke
				(width 0.1524)
				(type default)
			)
			(layer "F.SilkS")
		)
		(fp_line
			(start 1.03378 0.4826)
			(end -0.79248 0.4826)
			(stroke
				(width 0.1524)
				(type default)
			)
			(layer "F.SilkS")
		)
		(fp_line
			(start 1.16078 -0.4826)
			(end 1.16078 0.4826)
			(stroke
				(width 0.1524)
				(type default)
			)
			(layer "F.SilkS")
		)
		(fp_line
			(start 1.16078 0.4826)
			(end -0.64008 0.4826)
			(stroke
				(width 0.1524)
				(type default)
			)
			(layer "F.SilkS")
		)
		(fp_line
			(start -0.499872 -0.249936)
			(end 0.499872 -0.249936)
			(stroke
				(width 0.1)
				(type default)
			)
			(layer "F.Fab")
		)
		(fp_line
			(start -0.499872 0.249936)
			(end -0.499872 -0.249936)
			(stroke
				(width 0.1)
				(type default)
			)
			(layer "F.Fab")
		)
		(fp_line
			(start 0.499872 -0.249936)
			(end 0.499872 0.249936)
			(stroke
				(width 0.1)
				(type default)
			)
			(layer "F.Fab")
		)
		(fp_line
			(start 0.499872 0.249936)
			(end -0.499872 0.249936)
			(stroke
				(width 0.1)
				(type default)
			)
			(layer "F.Fab")
		)
		(pad "A" smd rect
			(at -0.47498 0)
			(size 0.6096 0.7112)
			(layers "F.Cu" "F.Mask" "F.Paste")
			(net "LED_PWRGD_PCH_PWROK_R")
		)
		(pad "C" smd rect
			(at 0.47498 0)
			(size 0.6096 0.7112)
			(layers "F.Cu" "F.Mask" "F.Paste")
			(net "LED_PWRGD_PCH_PWROK_R_D")
		)
	)
	(footprint ""
		(layer "F.Cu")
		(at 302.895 -419.10635 -90)
		(property "Reference" "R4120"
			(at 0 0 270)
			(layer "F.SilkS")
			(hide yes)
			(effects
				(font
					(size 1.27 1.27)
				)
			)
		)
		(property "Value" ""
			(at 0 0 270)
			(layer "F.Fab")
			(effects
				(font
					(size 1.27 1.27)
				)
			)
		)
		(duplicate_pad_numbers_are_jumpers no)
		(fp_line
			(start -0.7874 0.4064)
			(end -0.7874 -0.4064)
			(stroke
				(width 0.1524)
				(type default)
			)
			(layer "F.SilkS")
		)
		(fp_line
			(start 0.7874 0.4064)
			(end -0.7874 0.4064)
			(stroke
				(width 0.1524)
				(type default)
			)
			(layer "F.SilkS")
		)
		(fp_line
			(start -0.7874 -0.4064)
			(end 0.7874 -0.4064)
			(stroke
				(width 0.1524)
				(type default)
			)
			(layer "F.SilkS")
		)
		(fp_line
			(start 0.7874 -0.4064)
			(end 0.7874 0.4064)
			(stroke
				(width 0.1524)
				(type default)
			)
			(layer "F.SilkS")
		)
		(fp_line
			(start -0.67945 0.3048)
			(end -0.67945 -0.305054)
			(stroke
				(width 0.1)
				(type default)
			)
			(layer "F.Fab")
		)
		(fp_line
			(start -0.12065 0.3048)
			(end -0.67945 0.3048)
			(stroke
				(width 0.1)
				(type default)
			)
			(layer "F.Fab")
		)
		(fp_line
			(start 0.120396 0.3048)
			(end 0.120396 0.2794)
			(stroke
				(width 0.1)
				(type default)
			)
			(layer "F.Fab")
		)
		(fp_line
			(start 0.67945 0.3048)
			(end 0.120396 0.3048)
			(stroke
				(width 0.1)
				(type default)
			)
			(layer "F.Fab")
		)
		(fp_line
			(start -0.12065 0.2794)
			(end -0.12065 0.3048)
			(stroke
				(width 0.1)
				(type default)
			)
			(layer "F.Fab")
		)
		(fp_line
			(start 0.120396 0.2794)
			(end -0.12065 0.2794)
			(stroke
				(width 0.1)
				(type default)
			)
			(layer "F.Fab")
		)
		(fp_line
			(start -0.12065 -0.2794)
			(end 0.12065 -0.2794)
			(stroke
				(width 0.1)
				(type default)
			)
			(layer "F.Fab")
		)
		(fp_line
			(start 0.12065 -0.2794)
			(end 0.12065 -0.3048)
			(stroke
				(width 0.1)
				(type default)
			)
			(layer "F.Fab")
		)
		(fp_line
			(start 0.12065 -0.3048)
			(end 0.67945 -0.3048)
			(stroke
				(width 0.1)
				(type default)
			)
			(layer "F.Fab")
		)
		(fp_line
			(start 0.67945 -0.3048)
			(end 0.67945 0.3048)
			(stroke
				(width 0.1)
				(type default)
			)
			(layer "F.Fab")
		)
		(fp_line
			(start -0.67945 -0.305054)
			(end -0.12065 -0.305054)
			(stroke
				(width 0.1)
				(type default)
			)
			(layer "F.Fab")
		)
		(fp_line
			(start -0.12065 -0.305054)
			(end -0.12065 -0.2794)
			(stroke
				(width 0.1)
				(type default)
			)
			(layer "F.Fab")
		)
		(pad "1" smd circle
			(at -0.40005 0 270)
			(size 0 0)
			(layers "F.Cu" "F.Mask" "F.Paste")
			(net "GPU_3V3IO_RSVD0_FFU")
		)
		(pad "2" smd circle
			(at 0.40005 0 270)
			(size 0 0)
			(layers "F.Cu" "F.Mask" "F.Paste")
			(net "GND")
		)
	)
	(footprint ""
		(layer "F.Cu")
		(at 164.592 -23.713948)
		(property "Reference" "C1302"
			(at 0 0 0)
			(layer "F.SilkS")
			(hide yes)
			(effects
				(font
					(size 1.27 1.27)
				)
			)
		)
		(property "Value" ""
			(at 0 0 0)
			(layer "F.Fab")
			(effects
				(font
					(size 1.27 1.27)
				)
			)
		)
		(duplicate_pad_numbers_are_jumpers no)
		(fp_line
			(start -0.7874 -0.4064)
			(end 0.7874 -0.4064)
			(stroke
				(width 0.1524)
				(type default)
			)
			(layer "F.SilkS")
		)
		(fp_line
			(start -0.7874 0.4064)
			(end -0.7874 -0.4064)
			(stroke
				(width 0.1524)
				(type default)
			)
			(layer "F.SilkS")
		)
		(fp_line
			(start 0.7874 -0.4064)
			(end 0.7874 0.4064)
			(stroke
				(width 0.1524)
				(type default)
			)
			(layer "F.SilkS")
		)
		(fp_line
			(start 0.7874 0.4064)
			(end -0.7874 0.4064)
			(stroke
				(width 0.1524)
				(type default)
			)
			(layer "F.SilkS")
		)
		(fp_line
			(start -0.67945 -0.305054)
			(end -0.12065 -0.305054)
			(stroke
				(width 0.1)
				(type default)
			)
			(layer "F.Fab")
		)
		(fp_line
			(start -0.67945 0.3048)
			(end -0.67945 -0.305054)
			(stroke
				(width 0.1)
				(type default)
			)
			(layer "F.Fab")
		)
		(fp_line
			(start -0.12065 -0.305054)
			(end -0.12065 -0.2794)
			(stroke
				(width 0.1)
				(type default)
			)
			(layer "F.Fab")
		)
		(fp_line
			(start -0.12065 -0.2794)
			(end 0.12065 -0.2794)
			(stroke
				(width 0.1)
				(type default)
			)
			(layer "F.Fab")
		)
		(fp_line
			(start -0.12065 0.2794)
			(end -0.12065 0.3048)
			(stroke
				(width 0.1)
				(type default)
			)
			(layer "F.Fab")
		)
		(fp_line
			(start -0.12065 0.3048)
			(end -0.67945 0.3048)
			(stroke
				(width 0.1)
				(type default)
			)
			(layer "F.Fab")
		)
		(fp_line
			(start 0.120396 0.2794)
			(end -0.12065 0.2794)
			(stroke
				(width 0.1)
				(type default)
			)
			(layer "F.Fab")
		)
		(fp_line
			(start 0.120396 0.3048)
			(end 0.120396 0.2794)
			(stroke
				(width 0.1)
				(type default)
			)
			(layer "F.Fab")
		)
		(fp_line
			(start 0.12065 -0.3048)
			(end 0.67945 -0.3048)
			(stroke
				(width 0.1)
				(type default)
			)
			(layer "F.Fab")
		)
		(fp_line
			(start 0.12065 -0.2794)
			(end 0.12065 -0.3048)
			(stroke
				(width 0.1)
				(type default)
			)
			(layer "F.Fab")
		)
		(fp_line
			(start 0.67945 -0.3048)
			(end 0.67945 0.3048)
			(stroke
				(width 0.1)
				(type default)
			)
			(layer "F.Fab")
		)
		(fp_line
			(start 0.67945 0.3048)
			(end 0.120396 0.3048)
			(stroke
				(width 0.1)
				(type default)
			)
			(layer "F.Fab")
		)
		(pad "1" smd circle
			(at -0.40005 0)
			(size 0 0)
			(layers "F.Cu" "F.Mask" "F.Paste")
			(net "PVNN_TERM_CPU0")
		)
		(pad "2" smd circle
			(at 0.40005 0)
			(size 0 0)
			(layers "F.Cu" "F.Mask" "F.Paste")
			(net "GND")
		)
	)
	(footprint ""
		(layer "F.Cu")
		(at 272.08607 -97.063814)
		(property "Reference" "R113"
			(at 0 0 0)
			(layer "F.SilkS")
			(hide yes)
			(effects
				(font
					(size 1.27 1.27)
				)
			)
		)
		(property "Value" ""
			(at 0 0 0)
			(layer "F.Fab")
			(effects
				(font
					(size 1.27 1.27)
				)
			)
		)
		(duplicate_pad_numbers_are_jumpers no)
		(fp_line
			(start -0.7874 -0.4064)
			(end 0.7874 -0.4064)
			(stroke
				(width 0.1524)
				(type default)
			)
			(layer "F.SilkS")
		)
		(fp_line
			(start -0.7874 0.4064)
			(end -0.7874 -0.4064)
			(stroke
				(width 0.1524)
				(type default)
			)
			(layer "F.SilkS")
		)
		(fp_line
			(start 0.7874 -0.4064)
			(end 0.7874 0.4064)
			(stroke
				(width 0.1524)
				(type default)
			)
			(layer "F.SilkS")
		)
		(fp_line
			(start 0.7874 0.4064)
			(end -0.7874 0.4064)
			(stroke
				(width 0.1524)
				(type default)
			)
			(layer "F.SilkS")
		)
		(fp_line
			(start -0.67945 -0.305054)
			(end -0.12065 -0.305054)
			(stroke
				(width 0.1)
				(type default)
			)
			(layer "F.Fab")
		)
		(fp_line
			(start -0.67945 0.3048)
			(end -0.67945 -0.305054)
			(stroke
				(width 0.1)
				(type default)
			)
			(layer "F.Fab")
		)
		(fp_line
			(start -0.12065 -0.305054)
			(end -0.12065 -0.2794)
			(stroke
				(width 0.1)
				(type default)
			)
			(layer "F.Fab")
		)
		(fp_line
			(start -0.12065 -0.2794)
			(end 0.12065 -0.2794)
			(stroke
				(width 0.1)
				(type default)
			)
			(layer "F.Fab")
		)
		(fp_line
			(start -0.12065 0.2794)
			(end -0.12065 0.3048)
			(stroke
				(width 0.1)
				(type default)
			)
			(layer "F.Fab")
		)
		(fp_line
			(start -0.12065 0.3048)
			(end -0.67945 0.3048)
			(stroke
				(width 0.1)
				(type default)
			)
			(layer "F.Fab")
		)
		(fp_line
			(start 0.120396 0.2794)
			(end -0.12065 0.2794)
			(stroke
				(width 0.1)
				(type default)
			)
			(layer "F.Fab")
		)
		(fp_line
			(start 0.120396 0.3048)
			(end 0.120396 0.2794)
			(stroke
				(width 0.1)
				(type default)
			)
			(layer "F.Fab")
		)
		(fp_line
			(start 0.12065 -0.3048)
			(end 0.67945 -0.3048)
			(stroke
				(width 0.1)
				(type default)
			)
			(layer "F.Fab")
		)
		(fp_line
			(start 0.12065 -0.2794)
			(end 0.12065 -0.3048)
			(stroke
				(width 0.1)
				(type default)
			)
			(layer "F.Fab")
		)
		(fp_line
			(start 0.67945 -0.3048)
			(end 0.67945 0.3048)
			(stroke
				(width 0.1)
				(type default)
			)
			(layer "F.Fab")
		)
		(fp_line
			(start 0.67945 0.3048)
			(end 0.120396 0.3048)
			(stroke
				(width 0.1)
				(type default)
			)
			(layer "F.Fab")
		)
		(pad "1" smd circle
			(at -0.40005 0)
			(size 0 0)
			(layers "F.Cu" "F.Mask" "F.Paste")
			(net "FM_PLD_CLKS_OE_R_N")
		)
		(pad "2" smd circle
			(at 0.40005 0)
			(size 0 0)
			(layers "F.Cu" "F.Mask" "F.Paste")
			(net "FM_DB2000_OE_N")
		)
	)
)
